(kicad_pcb
	(version 20260206)
	(generator "pcbnew")
	(generator_version "10.0")
	(general
		(thickness 1.6)
		(legacy_teardrops no)
	)
	(paper "A4")
	(title_block
		(title "01162023_DA0F0TEBIF0_F0T_Expander_BD_F_brd_V02_OCP.brd")
		(comment 1 "Grand Teton / footprints 5754-5759 of 9728")
	)
	(layers
		(0 "F.Cu" signal "TOP")
		(4 "In1.Cu" signal "GND")
		(6 "In2.Cu" signal "VCC")
		(8 "In3.Cu" signal "VCC1")
		(10 "In4.Cu" signal "GND1")
		(12 "In5.Cu" signal "IN1")
		(14 "In6.Cu" signal "GND2")
		(16 "In7.Cu" signal "IN2")
		(18 "In8.Cu" signal "GND3")
		(20 "In9.Cu" signal "IN3")
		(22 "In10.Cu" signal "GND4")
		(24 "In11.Cu" signal "IN4")
		(26 "In12.Cu" signal "GND5")
		(28 "In13.Cu" signal "IN5")
		(30 "In14.Cu" signal "GND6")
		(32 "In15.Cu" signal "IN6")
		(34 "In16.Cu" signal "GND7")
		(2 "B.Cu" signal "BOTTOM")
		(9 "F.Adhes" user "F.Adhesive")
		(11 "B.Adhes" user "B.Adhesive")
		(13 "F.Paste" user "Package Geometry/Pastemask Top")
		(15 "B.Paste" user "Package Geometry/Pastemask Bottom")
		(5 "F.SilkS" user "Ref Des/Silkscreen Top")
		(7 "B.SilkS" user "Ref Des/Silkscreen Bottom")
		(1 "F.Mask" user "Board Geometry/Soldermask Top")
		(3 "B.Mask" user "Board Geometry/Soldermask Bottom")
		(17 "Dwgs.User" user "User.Drawings")
		(19 "Cmts.User" user "User.Comments")
		(21 "Eco1.User" user "User.Eco1")
		(23 "Eco2.User" user "User.Eco2")
		(25 "Edge.Cuts" user "Board Geometry/Outline")
		(27 "Margin" user)
		(31 "F.CrtYd" user "Package Geometry/Place Bound Top")
		(29 "B.CrtYd" user "Package Geometry/Place Bound Bottom")
		(35 "F.Fab" user "Ref Des/Assembly Top")
		(33 "B.Fab" user "Ref Des/Assembly Bottom")
	)
	(footprint ""
		(layer "F.Cu")
		(at 224.54743 -190.17869 90)
		(property "Reference" "C2629"
			(at 0 0 90)
			(layer "F.SilkS")
			(hide yes)
			(effects
				(font
					(size 1.27 1.27)
				)
			)
		)
		(property "Value" ""
			(at 0 0 90)
			(layer "F.Fab")
			(effects
				(font
					(size 1.27 1.27)
				)
			)
		)
		(duplicate_pad_numbers_are_jumpers no)
		(fp_line
			(start 0.7874 -0.4064)
			(end 0.7874 0.4064)
			(stroke
				(width 0.1524)
				(type default)
			)
			(layer "F.SilkS")
		)
		(fp_line
			(start -0.7874 -0.4064)
			(end 0.7874 -0.4064)
			(stroke
				(width 0.1524)
				(type default)
			)
			(layer "F.SilkS")
		)
		(fp_line
			(start 0.7874 0.4064)
			(end -0.7874 0.4064)
			(stroke
				(width 0.1524)
				(type default)
			)
			(layer "F.SilkS")
		)
		(fp_line
			(start -0.7874 0.4064)
			(end -0.7874 -0.4064)
			(stroke
				(width 0.1524)
				(type default)
			)
			(layer "F.SilkS")
		)
		(fp_line
			(start -0.12065 -0.305054)
			(end -0.12065 -0.2794)
			(stroke
				(width 0.1)
				(type default)
			)
			(layer "F.Fab")
		)
		(fp_line
			(start -0.67945 -0.305054)
			(end -0.12065 -0.305054)
			(stroke
				(width 0.1)
				(type default)
			)
			(layer "F.Fab")
		)
		(fp_line
			(start 0.67945 -0.3048)
			(end 0.67945 0.3048)
			(stroke
				(width 0.1)
				(type default)
			)
			(layer "F.Fab")
		)
		(fp_line
			(start 0.12065 -0.3048)
			(end 0.67945 -0.3048)
			(stroke
				(width 0.1)
				(type default)
			)
			(layer "F.Fab")
		)
		(fp_line
			(start 0.12065 -0.2794)
			(end 0.12065 -0.3048)
			(stroke
				(width 0.1)
				(type default)
			)
			(layer "F.Fab")
		)
		(fp_line
			(start -0.12065 -0.2794)
			(end 0.12065 -0.2794)
			(stroke
				(width 0.1)
				(type default)
			)
			(layer "F.Fab")
		)
		(fp_line
			(start 0.120396 0.2794)
			(end -0.12065 0.2794)
			(stroke
				(width 0.1)
				(type default)
			)
			(layer "F.Fab")
		)
		(fp_line
			(start -0.12065 0.2794)
			(end -0.12065 0.3048)
			(stroke
				(width 0.1)
				(type default)
			)
			(layer "F.Fab")
		)
		(fp_line
			(start 0.67945 0.3048)
			(end 0.120396 0.3048)
			(stroke
				(width 0.1)
				(type default)
			)
			(layer "F.Fab")
		)
		(fp_line
			(start 0.120396 0.3048)
			(end 0.120396 0.2794)
			(stroke
				(width 0.1)
				(type default)
			)
			(layer "F.Fab")
		)
		(fp_line
			(start -0.12065 0.3048)
			(end -0.67945 0.3048)
			(stroke
				(width 0.1)
				(type default)
			)
			(layer "F.Fab")
		)
		(fp_line
			(start -0.67945 0.3048)
			(end -0.67945 -0.305054)
			(stroke
				(width 0.1)
				(type default)
			)
			(layer "F.Fab")
		)
		(pad "1" smd circle
			(at -0.40005 0 90)
			(size 0 0)
			(layers "F.Cu" "F.Mask" "F.Paste")
			(net "GND")
		)
		(pad "2" smd circle
			(at 0.40005 0 90)
			(size 0 0)
			(layers "F.Cu" "F.Mask" "F.Paste")
			(net "P3V3_AUX")
		)
	)
	(footprint ""
		(layer "F.Cu")
		(at 216.401396 -106.36504)
		(property "Reference" "R723"
			(at 0 0 0)
			(layer "F.SilkS")
			(hide yes)
			(effects
				(font
					(size 1.27 1.27)
				)
			)
		)
		(property "Value" ""
			(at 0 0 0)
			(layer "F.Fab")
			(effects
				(font
					(size 1.27 1.27)
				)
			)
		)
		(duplicate_pad_numbers_are_jumpers no)
		(fp_line
			(start -0.7874 -0.4064)
			(end 0.7874 -0.4064)
			(stroke
				(width 0.1524)
				(type default)
			)
			(layer "F.SilkS")
		)
		(fp_line
			(start -0.7874 0.4064)
			(end -0.7874 -0.4064)
			(stroke
				(width 0.1524)
				(type default)
			)
			(layer "F.SilkS")
		)
		(fp_line
			(start 0.7874 -0.4064)
			(end 0.7874 0.4064)
			(stroke
				(width 0.1524)
				(type default)
			)
			(layer "F.SilkS")
		)
		(fp_line
			(start 0.7874 0.4064)
			(end -0.7874 0.4064)
			(stroke
				(width 0.1524)
				(type default)
			)
			(layer "F.SilkS")
		)
		(fp_line
			(start -0.67945 -0.305054)
			(end -0.12065 -0.305054)
			(stroke
				(width 0.1)
				(type default)
			)
			(layer "F.Fab")
		)
		(fp_line
			(start -0.67945 0.3048)
			(end -0.67945 -0.305054)
			(stroke
				(width 0.1)
				(type default)
			)
			(layer "F.Fab")
		)
		(fp_line
			(start -0.12065 -0.305054)
			(end -0.12065 -0.2794)
			(stroke
				(width 0.1)
				(type default)
			)
			(layer "F.Fab")
		)
		(fp_line
			(start -0.12065 -0.2794)
			(end 0.12065 -0.2794)
			(stroke
				(width 0.1)
				(type default)
			)
			(layer "F.Fab")
		)
		(fp_line
			(start -0.12065 0.2794)
			(end -0.12065 0.3048)
			(stroke
				(width 0.1)
				(type default)
			)
			(layer "F.Fab")
		)
		(fp_line
			(start -0.12065 0.3048)
			(end -0.67945 0.3048)
			(stroke
				(width 0.1)
				(type default)
			)
			(layer "F.Fab")
		)
		(fp_line
			(start 0.120396 0.2794)
			(end -0.12065 0.2794)
			(stroke
				(width 0.1)
				(type default)
			)
			(layer "F.Fab")
		)
		(fp_line
			(start 0.120396 0.3048)
			(end 0.120396 0.2794)
			(stroke
				(width 0.1)
				(type default)
			)
			(layer "F.Fab")
		)
		(fp_line
			(start 0.12065 -0.3048)
			(end 0.67945 -0.3048)
			(stroke
				(width 0.1)
				(type default)
			)
			(layer "F.Fab")
		)
		(fp_line
			(start 0.12065 -0.2794)
			(end 0.12065 -0.3048)
			(stroke
				(width 0.1)
				(type default)
			)
			(layer "F.Fab")
		)
		(fp_line
			(start 0.67945 -0.3048)
			(end 0.67945 0.3048)
			(stroke
				(width 0.1)
				(type default)
			)
			(layer "F.Fab")
		)
		(fp_line
			(start 0.67945 0.3048)
			(end 0.120396 0.3048)
			(stroke
				(width 0.1)
				(type default)
			)
			(layer "F.Fab")
		)
		(pad "1" smd circle
			(at -0.40005 0)
			(size 0 0)
			(layers "F.Cu" "F.Mask" "F.Paste")
			(net "P12V_NIC3")
		)
		(pad "2" smd circle
			(at 0.40005 0)
			(size 0 0)
			(layers "F.Cu" "F.Mask" "F.Paste")
			(net "P12V_NIC3_VIN_N")
		)
	)
	(footprint ""
		(layer "F.Cu")
		(at 270.807942 -157.3784 180)
		(property "Reference" "R216"
			(at 0 0 180)
			(layer "F.SilkS")
			(hide yes)
			(effects
				(font
					(size 1.27 1.27)
				)
			)
		)
		(property "Value" ""
			(at 0 0 180)
			(layer "F.Fab")
			(effects
				(font
					(size 1.27 1.27)
				)
			)
		)
		(duplicate_pad_numbers_are_jumpers no)
		(fp_line
			(start 0.7874 0.4064)
			(end -0.7874 0.4064)
			(stroke
				(width 0.1524)
				(type default)
			)
			(layer "F.SilkS")
		)
		(fp_line
			(start 0.7874 -0.4064)
			(end 0.7874 0.4064)
			(stroke
				(width 0.1524)
				(type default)
			)
			(layer "F.SilkS")
		)
		(fp_line
			(start -0.7874 0.4064)
			(end -0.7874 -0.4064)
			(stroke
				(width 0.1524)
				(type default)
			)
			(layer "F.SilkS")
		)
		(fp_line
			(start -0.7874 -0.4064)
			(end 0.7874 -0.4064)
			(stroke
				(width 0.1524)
				(type default)
			)
			(layer "F.SilkS")
		)
		(fp_line
			(start 0.67945 0.3048)
			(end 0.120396 0.3048)
			(stroke
				(width 0.1)
				(type default)
			)
			(layer "F.Fab")
		)
		(fp_line
			(start 0.67945 -0.3048)
			(end 0.67945 0.3048)
			(stroke
				(width 0.1)
				(type default)
			)
			(layer "F.Fab")
		)
		(fp_line
			(start 0.12065 -0.2794)
			(end 0.12065 -0.3048)
			(stroke
				(width 0.1)
				(type default)
			)
			(layer "F.Fab")
		)
		(fp_line
			(start 0.12065 -0.3048)
			(end 0.67945 -0.3048)
			(stroke
				(width 0.1)
				(type default)
			)
			(layer "F.Fab")
		)
		(fp_line
			(start 0.120396 0.3048)
			(end 0.120396 0.2794)
			(stroke
				(width 0.1)
				(type default)
			)
			(layer "F.Fab")
		)
		(fp_line
			(start 0.120396 0.2794)
			(end -0.12065 0.2794)
			(stroke
				(width 0.1)
				(type default)
			)
			(layer "F.Fab")
		)
		(fp_line
			(start -0.12065 0.3048)
			(end -0.67945 0.3048)
			(stroke
				(width 0.1)
				(type default)
			)
			(layer "F.Fab")
		)
		(fp_line
			(start -0.12065 0.2794)
			(end -0.12065 0.3048)
			(stroke
				(width 0.1)
				(type default)
			)
			(layer "F.Fab")
		)
		(fp_line
			(start -0.12065 -0.2794)
			(end 0.12065 -0.2794)
			(stroke
				(width 0.1)
				(type default)
			)
			(layer "F.Fab")
		)
		(fp_line
			(start -0.12065 -0.305054)
			(end -0.12065 -0.2794)
			(stroke
				(width 0.1)
				(type default)
			)
			(layer "F.Fab")
		)
		(fp_line
			(start -0.67945 0.3048)
			(end -0.67945 -0.305054)
			(stroke
				(width 0.1)
				(type default)
			)
			(layer "F.Fab")
		)
		(fp_line
			(start -0.67945 -0.305054)
			(end -0.12065 -0.305054)
			(stroke
				(width 0.1)
				(type default)
			)
			(layer "F.Fab")
		)
		(pad "1" smd circle
			(at -0.40005 0 180)
			(size 0 0)
			(layers "F.Cu" "F.Mask" "F.Paste")
			(net "NIC4_DATA_IN")
		)
		(pad "2" smd circle
			(at 0.40005 0 180)
			(size 0 0)
			(layers "F.Cu" "F.Mask" "F.Paste")
			(net "P3V3_NIC4")
		)
	)
	(footprint ""
		(layer "F.Cu")
		(at 373.761 -192.659 90)
		(property "Reference" "C3598"
			(at 0 0 90)
			(layer "F.SilkS")
			(hide yes)
			(effects
				(font
					(size 1.27 1.27)
				)
			)
		)
		(property "Value" ""
			(at 0 0 90)
			(layer "F.Fab")
			(effects
				(font
					(size 1.27 1.27)
				)
			)
		)
		(duplicate_pad_numbers_are_jumpers no)
		(fp_line
			(start 0.7874 -0.4064)
			(end 0.7874 0.4064)
			(stroke
				(width 0.1524)
				(type default)
			)
			(layer "F.SilkS")
		)
		(fp_line
			(start -0.7874 -0.4064)
			(end 0.7874 -0.4064)
			(stroke
				(width 0.1524)
				(type default)
			)
			(layer "F.SilkS")
		)
		(fp_line
			(start 0.7874 0.4064)
			(end -0.7874 0.4064)
			(stroke
				(width 0.1524)
				(type default)
			)
			(layer "F.SilkS")
		)
		(fp_line
			(start -0.7874 0.4064)
			(end -0.7874 -0.4064)
			(stroke
				(width 0.1524)
				(type default)
			)
			(layer "F.SilkS")
		)
		(fp_line
			(start -0.12065 -0.305054)
			(end -0.12065 -0.2794)
			(stroke
				(width 0.1)
				(type default)
			)
			(layer "F.Fab")
		)
		(fp_line
			(start -0.67945 -0.305054)
			(end -0.12065 -0.305054)
			(stroke
				(width 0.1)
				(type default)
			)
			(layer "F.Fab")
		)
		(fp_line
			(start 0.67945 -0.3048)
			(end 0.67945 0.3048)
			(stroke
				(width 0.1)
				(type default)
			)
			(layer "F.Fab")
		)
		(fp_line
			(start 0.12065 -0.3048)
			(end 0.67945 -0.3048)
			(stroke
				(width 0.1)
				(type default)
			)
			(layer "F.Fab")
		)
		(fp_line
			(start 0.12065 -0.2794)
			(end 0.12065 -0.3048)
			(stroke
				(width 0.1)
				(type default)
			)
			(layer "F.Fab")
		)
		(fp_line
			(start -0.12065 -0.2794)
			(end 0.12065 -0.2794)
			(stroke
				(width 0.1)
				(type default)
			)
			(layer "F.Fab")
		)
		(fp_line
			(start 0.120396 0.2794)
			(end -0.12065 0.2794)
			(stroke
				(width 0.1)
				(type default)
			)
			(layer "F.Fab")
		)
		(fp_line
			(start -0.12065 0.2794)
			(end -0.12065 0.3048)
			(stroke
				(width 0.1)
				(type default)
			)
			(layer "F.Fab")
		)
		(fp_line
			(start 0.67945 0.3048)
			(end 0.120396 0.3048)
			(stroke
				(width 0.1)
				(type default)
			)
			(layer "F.Fab")
		)
		(fp_line
			(start 0.120396 0.3048)
			(end 0.120396 0.2794)
			(stroke
				(width 0.1)
				(type default)
			)
			(layer "F.Fab")
		)
		(fp_line
			(start -0.12065 0.3048)
			(end -0.67945 0.3048)
			(stroke
				(width 0.1)
				(type default)
			)
			(layer "F.Fab")
		)
		(fp_line
			(start -0.67945 0.3048)
			(end -0.67945 -0.305054)
			(stroke
				(width 0.1)
				(type default)
			)
			(layer "F.Fab")
		)
		(pad "1" smd circle
			(at -0.40005 0 90)
			(size 0 0)
			(layers "F.Cu" "F.Mask" "F.Paste")
			(net "P3V3_AUX")
		)
		(pad "2" smd circle
			(at 0.40005 0 90)
			(size 0 0)
			(layers "F.Cu" "F.Mask" "F.Paste")
			(net "GND")
		)
	)
	(footprint ""
		(layer "F.Cu")
		(at 252.646434 -58.323734)
		(property "Reference" "PC401"
			(at 0 0 0)
			(layer "F.SilkS")
			(hide yes)
			(effects
				(font
					(size 1.27 1.27)
				)
			)
		)
		(property "Value" ""
			(at 0 0 0)
			(layer "F.Fab")
			(effects
				(font
					(size 1.27 1.27)
				)
			)
		)
		(duplicate_pad_numbers_are_jumpers no)
		(fp_line
			(start -1.524 -0.762)
			(end 1.524 -0.762)
			(stroke
				(width 0.1524)
				(type default)
			)
			(layer "F.SilkS")
		)
		(fp_line
			(start -1.524 0.762)
			(end -1.524 -0.762)
			(stroke
				(width 0.1524)
				(type default)
			)
			(layer "F.SilkS")
		)
		(fp_line
			(start 1.524 -0.762)
			(end 1.524 0.762)
			(stroke
				(width 0.1524)
				(type default)
			)
			(layer "F.SilkS")
		)
		(fp_line
			(start 1.524 0.762)
			(end -1.524 0.762)
			(stroke
				(width 0.1524)
				(type default)
			)
			(layer "F.SilkS")
		)
		(fp_line
			(start -1.1049 -0.724916)
			(end -1.1049 0.724916)
			(stroke
				(width 0.1)
				(type default)
			)
			(layer "F.Fab")
		)
		(fp_line
			(start -1.1049 0.724916)
			(end 1.1049 0.724916)
			(stroke
				(width 0.1)
				(type default)
			)
			(layer "F.Fab")
		)
		(fp_line
			(start 1.1049 -0.724916)
			(end -1.1049 -0.724916)
			(stroke
				(width 0.1)
				(type default)
			)
			(layer "F.Fab")
		)
		(fp_line
			(start 1.1049 0.724916)
			(end 1.1049 -0.724916)
			(stroke
				(width 0.1)
				(type default)
			)
			(layer "F.Fab")
		)
		(pad "1" smd rect
			(at -0.889 0 180)
			(size 1.016 1.27)
			(layers "F.Cu" "F.Mask" "F.Paste")
			(net "GND")
		)
		(pad "2" smd rect
			(at 0.889 0 180)
			(size 1.016 1.27)
			(layers "F.Cu" "F.Mask" "F.Paste")
			(net "P12V_AUX")
		)
	)
	(footprint ""
		(layer "F.Cu")
		(at 87.175848 -450.754496 180)
		(property "Reference" "X20"
			(at -0.1778 -1.92913 180)
			(unlocked yes)
			(layer "F.SilkS")
			(effects
				(font
					(size 0.7874 0.5842)
					(thickness 0.1524)
				)
				(justify left)
			)
		)
		(property "Value" ""
			(at 0 0 180)
			(layer "F.Fab")
			(effects
				(font
					(size 1.27 1.27)
				)
			)
		)
		(property "Device Type" "TP_TDR_4P_FTS_MPKT4_H025P0200_IO_TP15_TP_TDR_4P_DIP"
			(at 1.30175 1.27 270)
			(unlocked yes)
			(layer "F.Fab")
			(hide yes)
			(effects
				(font
					(size 0.635 0.4064)
					(thickness 0.1524)
				)
			)
		)
		(property "User Part Number" "TP15"
			(at 1.30175 1.27 270)
			(unlocked yes)
			(layer "Cmts.User")
			(hide yes)
			(effects
				(font
					(size 0.635 0.4064)
					(thickness 0.1524)
				)
			)
		)
		(duplicate_pad_numbers_are_jumpers no)
		(fp_line
			(start 2.54 3.81)
			(end 2.54 3.6703)
			(stroke
				(width 0.1524)
				(type default)
			)
			(layer "F.SilkS")
		)
		(fp_line
			(start 2.54 1.4097)
			(end 2.54 1.1303)
			(stroke
				(width 0.1524)
				(type default)
			)
			(layer "F.SilkS")
		)
		(fp_line
			(start 2.54 -1.1303)
			(end 2.54 -1.27)
			(stroke
				(width 0.1524)
				(type default)
			)
			(layer "F.SilkS")
		)
		(fp_line
			(start 2.54 -1.27)
			(end 0 -1.27)
			(stroke
				(width 0.1524)
				(type default)
			)
			(layer "F.SilkS")
		)
		(fp_line
			(start 0 3.81)
			(end 2.54 3.81)
			(stroke
				(width 0.1524)
				(type default)
			)
			(layer "F.SilkS")
		)
		(fp_line
			(start 0 3.175)
			(end 0 3.81)
			(stroke
				(width 0.1524)
				(type default)
			)
			(layer "F.SilkS")
		)
		(fp_line
			(start 0 0.635)
			(end 0 1.905)
			(stroke
				(width 0.1524)
				(type default)
			)
			(layer "F.SilkS")
		)
		(fp_line
			(start 0 -1.27)
			(end 0 -0.635)
			(stroke
				(width 0.1524)
				(type default)
			)
			(layer "F.SilkS")
		)
		(fp_poly
			(pts
				(xy -0.761746 0) (xy -2.285746 -0.762) (xy -2.285746 0.762)
			)
			(stroke
				(width 0)
				(type default)
			)
			(fill yes)
			(layer "F.SilkS")
		)
		(fp_line
			(start 2.54 3.81)
			(end 2.54 -1.27)
			(stroke
				(width 0.1)
				(type default)
			)
			(layer "F.Fab")
		)
		(fp_line
			(start 2.54 -1.27)
			(end 0 -1.27)
			(stroke
				(width 0.1)
				(type default)
			)
			(layer "F.Fab")
		)
		(fp_line
			(start 0 3.81)
			(end 2.54 3.81)
			(stroke
				(width 0.1)
				(type default)
			)
			(layer "F.Fab")
		)
		(fp_line
			(start 0 -1.27)
			(end 0 3.81)
			(stroke
				(width 0.1)
				(type default)
			)
			(layer "F.Fab")
		)
		(fp_poly
			(pts
				(xy -0.761746 0) (xy -2.285746 -0.762) (xy -2.285746 0.762)
			)
			(stroke
				(width 0)
				(type default)
			)
			(fill yes)
			(layer "F.Fab")
		)
		(pad "1" thru_hole circle
			(at 0 0 180)
			(size 1.0033 1.0033)
			(drill 0.249936)
			(layers "*.Cu" "*.Mask")
			(remove_unused_layers no)
			(net "TDR_DIFF_85_IN3_DIP")
			(clearance 0.10795)
			(thermal_gap 0.10795)
			(padstack
				(mode front_inner_back)
				(layer "Inner"
					(shape circle)
					(size 0.8001 0.8001)
					(clearance 0.1524)
				)
				(layer "B.Cu"
					(shape circle)
					(size 1.0033 1.0033)
					(clearance 0.10795)
				)
			)
		)
		(pad "2" thru_hole circle
			(at 2.54 0 180)
			(size 1.9939 1.9939)
			(drill 0.249936)
			(layers "*.Cu" "*.Mask")
			(remove_unused_layers no)
			(net "COUPON_GND1")
			(clearance 0.10795)
			(thermal_gap 0.10795)
			(padstack
				(mode front_inner_back)
				(layer "Inner"
					(shape circle)
					(size 0.8001 0.8001)
					(clearance 0.1524)
				)
				(layer "B.Cu"
					(shape circle)
					(size 1.9939 1.9939)
					(clearance 0.10795)
				)
			)
		)
		(pad "3" thru_hole circle
			(at 2.54 2.54 180)
			(size 1.9939 1.9939)
			(drill 0.249936)
			(layers "*.Cu" "*.Mask")
			(remove_unused_layers no)
			(net "COUPON_GND1")
			(clearance 0.10795)
			(thermal_gap 0.10795)
			(padstack
				(mode front_inner_back)
				(layer "Inner"
					(shape circle)
					(size 0.8001 0.8001)
					(clearance 0.1524)
				)
				(layer "B.Cu"
					(shape circle)
					(size 1.9939 1.9939)
					(clearance 0.10795)
				)
			)
		)
		(pad "4" thru_hole circle
			(at 0 2.54 180)
			(size 1.0033 1.0033)
			(drill 0.249936)
			(layers "*.Cu" "*.Mask")
			(remove_unused_layers no)
			(net "TDR_DIFF_85_IN3_DIN")
			(clearance 0.10795)
			(thermal_gap 0.10795)
			(padstack
				(mode front_inner_back)
				(layer "Inner"
					(shape circle)
					(size 0.8001 0.8001)
					(clearance 0.1524)
				)
				(layer "B.Cu"
					(shape circle)
					(size 1.0033 1.0033)
					(clearance 0.10795)
				)
			)
		)
	)
)
